(kicad_pcb
	(version 20260206)
	(generator "pcbnew")
	(generator_version "10.0")
	(general
		(thickness 1.6)
		(legacy_teardrops no)
	)
	(paper "A4")
	(title_block
		(title "03242023_DA0F0TMBIJ0_F0T_Motherboard_J_brd_V01_OCP.brd")
		(comment 1 "Grand Teton / footprints 4697-4704 of 6105")
	)
	(layers
		(0 "F.Cu" signal "TOP")
		(4 "In1.Cu" signal "GND")
		(6 "In2.Cu" signal "IN1")
		(8 "In3.Cu" signal "GND1")
		(10 "In4.Cu" signal "IN2")
		(12 "In5.Cu" signal "GND2")
		(14 "In6.Cu" signal "IN3")
		(16 "In7.Cu" signal "GND3")
		(18 "In8.Cu" signal "VCC")
		(20 "In9.Cu" signal "VCC1")
		(22 "In10.Cu" signal "GND4")
		(24 "In11.Cu" signal "IN4")
		(26 "In12.Cu" signal "GND5")
		(28 "In13.Cu" signal "IN5")
		(30 "In14.Cu" signal "GND6")
		(32 "In15.Cu" signal "IN6")
		(34 "In16.Cu" signal "GND7")
		(2 "B.Cu" signal "BOTTOM")
		(9 "F.Adhes" user "F.Adhesive")
		(11 "B.Adhes" user "B.Adhesive")
		(13 "F.Paste" user "Package Geometry/Pastemask Top")
		(15 "B.Paste" user "Package Geometry/Pastemask Bottom")
		(5 "F.SilkS" user "Ref Des/Silkscreen Top")
		(7 "B.SilkS" user "Ref Des/Silkscreen Bottom")
		(1 "F.Mask" user "Board Geometry/Soldermask Top")
		(3 "B.Mask" user "Board Geometry/Soldermask Bottom")
		(17 "Dwgs.User" user "User.Drawings")
		(19 "Cmts.User" user "User.Comments")
		(21 "Eco1.User" user "User.Eco1")
		(23 "Eco2.User" user "User.Eco2")
		(25 "Edge.Cuts" user "Board Geometry/Outline")
		(27 "Margin" user)
		(31 "F.CrtYd" user "Package Geometry/Place Bound Top")
		(29 "B.CrtYd" user "Package Geometry/Place Bound Bottom")
		(35 "F.Fab" user "Ref Des/Assembly Top")
		(33 "B.Fab" user "Ref Des/Assembly Bottom")
	)
	(footprint ""
		(layer "B.Cu")
		(at 367.898934 -255.853946 -90)
		(property "Reference" "C361"
			(at 0 0 90)
			(layer "B.SilkS")
			(hide yes)
			(effects
				(font
					(size 1.27 1.27)
				)
				(justify mirror)
			)
		)
		(property "Value" ""
			(at 0 0 90)
			(layer "B.Fab")
			(effects
				(font
					(size 1.27 1.27)
				)
				(justify mirror)
			)
		)
		(duplicate_pad_numbers_are_jumpers no)
		(fp_line
			(start -1.524 0.762)
			(end 1.524 0.762)
			(stroke
				(width 0.1524)
				(type default)
			)
			(layer "B.SilkS")
		)
		(fp_line
			(start 1.524 0.762)
			(end 1.524 -0.762)
			(stroke
				(width 0.1524)
				(type default)
			)
			(layer "B.SilkS")
		)
		(fp_line
			(start -1.524 -0.762)
			(end -1.524 0.762)
			(stroke
				(width 0.1524)
				(type default)
			)
			(layer "B.SilkS")
		)
		(fp_line
			(start 1.524 -0.762)
			(end -1.524 -0.762)
			(stroke
				(width 0.1524)
				(type default)
			)
			(layer "B.SilkS")
		)
		(fp_line
			(start -1.1049 0.724916)
			(end -1.1049 -0.724916)
			(stroke
				(width 0.1)
				(type default)
			)
			(layer "B.Fab")
		)
		(fp_line
			(start 1.1049 0.724916)
			(end -1.1049 0.724916)
			(stroke
				(width 0.1)
				(type default)
			)
			(layer "B.Fab")
		)
		(fp_line
			(start -1.1049 -0.724916)
			(end 1.1049 -0.724916)
			(stroke
				(width 0.1)
				(type default)
			)
			(layer "B.Fab")
		)
		(fp_line
			(start 1.1049 -0.724916)
			(end 1.1049 0.724916)
			(stroke
				(width 0.1)
				(type default)
			)
			(layer "B.Fab")
		)
		(pad "1" smd rect
			(at 0.889 0 270)
			(size 1.016 1.27)
			(layers "B.Cu" "B.Mask" "B.Paste")
			(net "PVCCIN_CPU0")
		)
		(pad "2" smd rect
			(at -0.889 0 270)
			(size 1.016 1.27)
			(layers "B.Cu" "B.Mask" "B.Paste")
			(net "GND")
		)
	)
	(footprint ""
		(layer "B.Cu")
		(at 110.31855 -413.110426 180)
		(property "Reference" "C2330"
			(at 0 0 0)
			(layer "B.SilkS")
			(hide yes)
			(effects
				(font
					(size 1.27 1.27)
				)
				(justify mirror)
			)
		)
		(property "Value" ""
			(at 0 0 0)
			(layer "B.Fab")
			(effects
				(font
					(size 1.27 1.27)
				)
				(justify mirror)
			)
		)
		(duplicate_pad_numbers_are_jumpers no)
		(fp_line
			(start 0.7874 0.4064)
			(end 0.7874 -0.4064)
			(stroke
				(width 0.1524)
				(type default)
			)
			(layer "B.SilkS")
		)
		(fp_line
			(start 0.7874 -0.4064)
			(end -0.7874 -0.4064)
			(stroke
				(width 0.1524)
				(type default)
			)
			(layer "B.SilkS")
		)
		(fp_line
			(start -0.7874 0.4064)
			(end 0.7874 0.4064)
			(stroke
				(width 0.1524)
				(type default)
			)
			(layer "B.SilkS")
		)
		(fp_line
			(start -0.7874 -0.4064)
			(end -0.7874 0.4064)
			(stroke
				(width 0.1524)
				(type default)
			)
			(layer "B.SilkS")
		)
		(fp_line
			(start 0.67945 0.3048)
			(end 0.67945 -0.305054)
			(stroke
				(width 0.1)
				(type default)
			)
			(layer "B.Fab")
		)
		(fp_line
			(start 0.67945 -0.305054)
			(end 0.12065 -0.305054)
			(stroke
				(width 0.1)
				(type default)
			)
			(layer "B.Fab")
		)
		(fp_line
			(start 0.12065 0.3048)
			(end 0.67945 0.3048)
			(stroke
				(width 0.1)
				(type default)
			)
			(layer "B.Fab")
		)
		(fp_line
			(start 0.12065 0.2794)
			(end 0.12065 0.3048)
			(stroke
				(width 0.1)
				(type default)
			)
			(layer "B.Fab")
		)
		(fp_line
			(start 0.12065 -0.2794)
			(end -0.12065 -0.2794)
			(stroke
				(width 0.1)
				(type default)
			)
			(layer "B.Fab")
		)
		(fp_line
			(start 0.12065 -0.305054)
			(end 0.12065 -0.2794)
			(stroke
				(width 0.1)
				(type default)
			)
			(layer "B.Fab")
		)
		(fp_line
			(start -0.120396 0.3048)
			(end -0.120396 0.2794)
			(stroke
				(width 0.1)
				(type default)
			)
			(layer "B.Fab")
		)
		(fp_line
			(start -0.120396 0.2794)
			(end 0.12065 0.2794)
			(stroke
				(width 0.1)
				(type default)
			)
			(layer "B.Fab")
		)
		(fp_line
			(start -0.12065 -0.2794)
			(end -0.12065 -0.3048)
			(stroke
				(width 0.1)
				(type default)
			)
			(layer "B.Fab")
		)
		(fp_line
			(start -0.12065 -0.3048)
			(end -0.67945 -0.3048)
			(stroke
				(width 0.1)
				(type default)
			)
			(layer "B.Fab")
		)
		(fp_line
			(start -0.67945 0.3048)
			(end -0.120396 0.3048)
			(stroke
				(width 0.1)
				(type default)
			)
			(layer "B.Fab")
		)
		(fp_line
			(start -0.67945 -0.3048)
			(end -0.67945 0.3048)
			(stroke
				(width 0.1)
				(type default)
			)
			(layer "B.Fab")
		)
		(pad "1" smd circle
			(at 0.40005 0)
			(size 0 0)
			(layers "B.Cu" "B.Mask" "B.Paste")
			(net "P3V3_9ZXL045_VDD")
		)
		(pad "2" smd circle
			(at -0.40005 0)
			(size 0 0)
			(layers "B.Cu" "B.Mask" "B.Paste")
			(net "GND")
		)
	)
	(footprint ""
		(layer "B.Cu")
		(at 138.921998 -342.936576 90)
		(property "Reference" "PC489_P1_8"
			(at 0 0 90)
			(layer "B.SilkS")
			(hide yes)
			(effects
				(font
					(size 1.27 1.27)
				)
				(justify mirror)
			)
		)
		(property "Value" ""
			(at 0 0 90)
			(layer "B.Fab")
			(effects
				(font
					(size 1.27 1.27)
				)
				(justify mirror)
			)
		)
		(duplicate_pad_numbers_are_jumpers no)
		(fp_line
			(start 1.524 -0.762)
			(end -1.524 -0.762)
			(stroke
				(width 0.1524)
				(type default)
			)
			(layer "B.SilkS")
		)
		(fp_line
			(start -1.524 -0.762)
			(end -1.524 0.762)
			(stroke
				(width 0.1524)
				(type default)
			)
			(layer "B.SilkS")
		)
		(fp_line
			(start 1.524 0.762)
			(end 1.524 -0.762)
			(stroke
				(width 0.1524)
				(type default)
			)
			(layer "B.SilkS")
		)
		(fp_line
			(start -1.524 0.762)
			(end 1.524 0.762)
			(stroke
				(width 0.1524)
				(type default)
			)
			(layer "B.SilkS")
		)
		(fp_line
			(start 1.1049 -0.724916)
			(end 1.1049 0.724916)
			(stroke
				(width 0.1)
				(type default)
			)
			(layer "B.Fab")
		)
		(fp_line
			(start -1.1049 -0.724916)
			(end 1.1049 -0.724916)
			(stroke
				(width 0.1)
				(type default)
			)
			(layer "B.Fab")
		)
		(fp_line
			(start 1.1049 0.724916)
			(end -1.1049 0.724916)
			(stroke
				(width 0.1)
				(type default)
			)
			(layer "B.Fab")
		)
		(fp_line
			(start -1.1049 0.724916)
			(end -1.1049 -0.724916)
			(stroke
				(width 0.1)
				(type default)
			)
			(layer "B.Fab")
		)
		(pad "1" smd rect
			(at 0.889 0 90)
			(size 1.016 1.27)
			(layers "B.Cu" "B.Mask" "B.Paste")
			(net "SW_P12V_PVCCIN_CPU1_FLT")
		)
		(pad "2" smd rect
			(at -0.889 0 90)
			(size 1.016 1.27)
			(layers "B.Cu" "B.Mask" "B.Paste")
			(net "GND")
		)
	)
	(footprint ""
		(layer "B.Cu")
		(at 416.02914 -178.336194)
		(property "Reference" "PC198_P0_2"
			(at 0 0 0)
			(layer "B.SilkS")
			(hide yes)
			(effects
				(font
					(size 1.27 1.27)
				)
				(justify mirror)
			)
		)
		(property "Value" ""
			(at 0 0 0)
			(layer "B.Fab")
			(effects
				(font
					(size 1.27 1.27)
				)
				(justify mirror)
			)
		)
		(duplicate_pad_numbers_are_jumpers no)
		(fp_line
			(start -1.524 -0.762)
			(end -1.524 0.762)
			(stroke
				(width 0.1524)
				(type default)
			)
			(layer "B.SilkS")
		)
		(fp_line
			(start -1.524 0.762)
			(end 1.524 0.762)
			(stroke
				(width 0.1524)
				(type default)
			)
			(layer "B.SilkS")
		)
		(fp_line
			(start 1.524 -0.762)
			(end -1.524 -0.762)
			(stroke
				(width 0.1524)
				(type default)
			)
			(layer "B.SilkS")
		)
		(fp_line
			(start 1.524 0.762)
			(end 1.524 -0.762)
			(stroke
				(width 0.1524)
				(type default)
			)
			(layer "B.SilkS")
		)
		(fp_line
			(start -1.1049 -0.724916)
			(end 1.1049 -0.724916)
			(stroke
				(width 0.1)
				(type default)
			)
			(layer "B.Fab")
		)
		(fp_line
			(start -1.1049 0.724916)
			(end -1.1049 -0.724916)
			(stroke
				(width 0.1)
				(type default)
			)
			(layer "B.Fab")
		)
		(fp_line
			(start 1.1049 -0.724916)
			(end 1.1049 0.724916)
			(stroke
				(width 0.1)
				(type default)
			)
			(layer "B.Fab")
		)
		(fp_line
			(start 1.1049 0.724916)
			(end -1.1049 0.724916)
			(stroke
				(width 0.1)
				(type default)
			)
			(layer "B.Fab")
		)
		(pad "1" smd rect
			(at 0.889 0)
			(size 1.016 1.27)
			(layers "B.Cu" "B.Mask" "B.Paste")
			(net "SW_P12V_PVCCINFAON_CPU0_FLT")
		)
		(pad "2" smd rect
			(at -0.889 0)
			(size 1.016 1.27)
			(layers "B.Cu" "B.Mask" "B.Paste")
			(net "GND")
		)
	)
	(footprint ""
		(layer "B.Cu")
		(at 104.463088 -210.194144)
		(property "Reference" "C456"
			(at 0 0 0)
			(layer "B.SilkS")
			(hide yes)
			(effects
				(font
					(size 1.27 1.27)
				)
				(justify mirror)
			)
		)
		(property "Value" ""
			(at 0 0 0)
			(layer "B.Fab")
			(effects
				(font
					(size 1.27 1.27)
				)
				(justify mirror)
			)
		)
		(duplicate_pad_numbers_are_jumpers no)
		(fp_line
			(start -1.524 -0.762)
			(end -1.524 0.762)
			(stroke
				(width 0.1524)
				(type default)
			)
			(layer "B.SilkS")
		)
		(fp_line
			(start -1.524 0.762)
			(end 1.524 0.762)
			(stroke
				(width 0.1524)
				(type default)
			)
			(layer "B.SilkS")
		)
		(fp_line
			(start 1.524 -0.762)
			(end -1.524 -0.762)
			(stroke
				(width 0.1524)
				(type default)
			)
			(layer "B.SilkS")
		)
		(fp_line
			(start 1.524 0.762)
			(end 1.524 -0.762)
			(stroke
				(width 0.1524)
				(type default)
			)
			(layer "B.SilkS")
		)
		(fp_line
			(start -1.1049 -0.724916)
			(end 1.1049 -0.724916)
			(stroke
				(width 0.1)
				(type default)
			)
			(layer "B.Fab")
		)
		(fp_line
			(start -1.1049 0.724916)
			(end -1.1049 -0.724916)
			(stroke
				(width 0.1)
				(type default)
			)
			(layer "B.Fab")
		)
		(fp_line
			(start 1.1049 -0.724916)
			(end 1.1049 0.724916)
			(stroke
				(width 0.1)
				(type default)
			)
			(layer "B.Fab")
		)
		(fp_line
			(start 1.1049 0.724916)
			(end -1.1049 0.724916)
			(stroke
				(width 0.1)
				(type default)
			)
			(layer "B.Fab")
		)
		(pad "1" smd rect
			(at 0.889 0)
			(size 1.016 1.27)
			(layers "B.Cu" "B.Mask" "B.Paste")
			(net "PVCCFA_EHV_CPU1")
		)
		(pad "2" smd rect
			(at -0.889 0)
			(size 1.016 1.27)
			(layers "B.Cu" "B.Mask" "B.Paste")
			(net "GND")
		)
	)
	(footprint ""
		(layer "B.Cu")
		(at 111.83112 -416.048698 90)
		(property "Reference" "C2333"
			(at 0 0 90)
			(layer "B.SilkS")
			(hide yes)
			(effects
				(font
					(size 1.27 1.27)
				)
				(justify mirror)
			)
		)
		(property "Value" ""
			(at 0 0 90)
			(layer "B.Fab")
			(effects
				(font
					(size 1.27 1.27)
				)
				(justify mirror)
			)
		)
		(duplicate_pad_numbers_are_jumpers no)
		(fp_line
			(start 0.7874 -0.4064)
			(end -0.7874 -0.4064)
			(stroke
				(width 0.1524)
				(type default)
			)
			(layer "B.SilkS")
		)
		(fp_line
			(start -0.7874 -0.4064)
			(end -0.7874 0.4064)
			(stroke
				(width 0.1524)
				(type default)
			)
			(layer "B.SilkS")
		)
		(fp_line
			(start 0.7874 0.4064)
			(end 0.7874 -0.4064)
			(stroke
				(width 0.1524)
				(type default)
			)
			(layer "B.SilkS")
		)
		(fp_line
			(start -0.7874 0.4064)
			(end 0.7874 0.4064)
			(stroke
				(width 0.1524)
				(type default)
			)
			(layer "B.SilkS")
		)
		(fp_line
			(start 0.67945 -0.305054)
			(end 0.12065 -0.305054)
			(stroke
				(width 0.1)
				(type default)
			)
			(layer "B.Fab")
		)
		(fp_line
			(start 0.12065 -0.305054)
			(end 0.12065 -0.2794)
			(stroke
				(width 0.1)
				(type default)
			)
			(layer "B.Fab")
		)
		(fp_line
			(start -0.12065 -0.3048)
			(end -0.67945 -0.3048)
			(stroke
				(width 0.1)
				(type default)
			)
			(layer "B.Fab")
		)
		(fp_line
			(start -0.67945 -0.3048)
			(end -0.67945 0.3048)
			(stroke
				(width 0.1)
				(type default)
			)
			(layer "B.Fab")
		)
		(fp_line
			(start 0.12065 -0.2794)
			(end -0.12065 -0.2794)
			(stroke
				(width 0.1)
				(type default)
			)
			(layer "B.Fab")
		)
		(fp_line
			(start -0.12065 -0.2794)
			(end -0.12065 -0.3048)
			(stroke
				(width 0.1)
				(type default)
			)
			(layer "B.Fab")
		)
		(fp_line
			(start 0.12065 0.2794)
			(end 0.12065 0.3048)
			(stroke
				(width 0.1)
				(type default)
			)
			(layer "B.Fab")
		)
		(fp_line
			(start -0.120396 0.2794)
			(end 0.12065 0.2794)
			(stroke
				(width 0.1)
				(type default)
			)
			(layer "B.Fab")
		)
		(fp_line
			(start 0.67945 0.3048)
			(end 0.67945 -0.305054)
			(stroke
				(width 0.1)
				(type default)
			)
			(layer "B.Fab")
		)
		(fp_line
			(start 0.12065 0.3048)
			(end 0.67945 0.3048)
			(stroke
				(width 0.1)
				(type default)
			)
			(layer "B.Fab")
		)
		(fp_line
			(start -0.120396 0.3048)
			(end -0.120396 0.2794)
			(stroke
				(width 0.1)
				(type default)
			)
			(layer "B.Fab")
		)
		(fp_line
			(start -0.67945 0.3048)
			(end -0.120396 0.3048)
			(stroke
				(width 0.1)
				(type default)
			)
			(layer "B.Fab")
		)
		(pad "1" smd circle
			(at 0.40005 0 270)
			(size 0 0)
			(layers "B.Cu" "B.Mask" "B.Paste")
			(net "P3V3_9ZXL045_VDD")
		)
		(pad "2" smd circle
			(at -0.40005 0 270)
			(size 0 0)
			(layers "B.Cu" "B.Mask" "B.Paste")
			(net "GND")
		)
	)
	(footprint ""
		(layer "B.Cu")
		(at 430.600104 -136.526778 180)
		(property "Reference" "C3276"
			(at 0 0 0)
			(layer "B.SilkS")
			(hide yes)
			(effects
				(font
					(size 1.27 1.27)
				)
				(justify mirror)
			)
		)
		(property "Value" ""
			(at 0 0 0)
			(layer "B.Fab")
			(effects
				(font
					(size 1.27 1.27)
				)
				(justify mirror)
			)
		)
		(duplicate_pad_numbers_are_jumpers no)
		(fp_line
			(start 0.7874 0.4064)
			(end 0.7874 -0.4064)
			(stroke
				(width 0.1524)
				(type default)
			)
			(layer "B.SilkS")
		)
		(fp_line
			(start 0.7874 -0.4064)
			(end -0.7874 -0.4064)
			(stroke
				(width 0.1524)
				(type default)
			)
			(layer "B.SilkS")
		)
		(fp_line
			(start -0.7874 0.4064)
			(end 0.7874 0.4064)
			(stroke
				(width 0.1524)
				(type default)
			)
			(layer "B.SilkS")
		)
		(fp_line
			(start -0.7874 -0.4064)
			(end -0.7874 0.4064)
			(stroke
				(width 0.1524)
				(type default)
			)
			(layer "B.SilkS")
		)
		(fp_line
			(start 0.67945 0.3048)
			(end 0.67945 -0.305054)
			(stroke
				(width 0.1)
				(type default)
			)
			(layer "B.Fab")
		)
		(fp_line
			(start 0.67945 -0.305054)
			(end 0.12065 -0.305054)
			(stroke
				(width 0.1)
				(type default)
			)
			(layer "B.Fab")
		)
		(fp_line
			(start 0.12065 0.3048)
			(end 0.67945 0.3048)
			(stroke
				(width 0.1)
				(type default)
			)
			(layer "B.Fab")
		)
		(fp_line
			(start 0.12065 0.2794)
			(end 0.12065 0.3048)
			(stroke
				(width 0.1)
				(type default)
			)
			(layer "B.Fab")
		)
		(fp_line
			(start 0.12065 -0.2794)
			(end -0.12065 -0.2794)
			(stroke
				(width 0.1)
				(type default)
			)
			(layer "B.Fab")
		)
		(fp_line
			(start 0.12065 -0.305054)
			(end 0.12065 -0.2794)
			(stroke
				(width 0.1)
				(type default)
			)
			(layer "B.Fab")
		)
		(fp_line
			(start -0.120396 0.3048)
			(end -0.120396 0.2794)
			(stroke
				(width 0.1)
				(type default)
			)
			(layer "B.Fab")
		)
		(fp_line
			(start -0.120396 0.2794)
			(end 0.12065 0.2794)
			(stroke
				(width 0.1)
				(type default)
			)
			(layer "B.Fab")
		)
		(fp_line
			(start -0.12065 -0.2794)
			(end -0.12065 -0.3048)
			(stroke
				(width 0.1)
				(type default)
			)
			(layer "B.Fab")
		)
		(fp_line
			(start -0.12065 -0.3048)
			(end -0.67945 -0.3048)
			(stroke
				(width 0.1)
				(type default)
			)
			(layer "B.Fab")
		)
		(fp_line
			(start -0.67945 0.3048)
			(end -0.120396 0.3048)
			(stroke
				(width 0.1)
				(type default)
			)
			(layer "B.Fab")
		)
		(fp_line
			(start -0.67945 -0.3048)
			(end -0.67945 0.3048)
			(stroke
				(width 0.1)
				(type default)
			)
			(layer "B.Fab")
		)
		(pad "1" smd circle
			(at 0.40005 0)
			(size 0 0)
			(layers "B.Cu" "B.Mask" "B.Paste")
			(net "PWRGD_PVCCFA_EHV_CPU0_R")
		)
		(pad "2" smd circle
			(at -0.40005 0)
			(size 0 0)
			(layers "B.Cu" "B.Mask" "B.Paste")
			(net "GND")
		)
	)
	(footprint ""
		(layer "B.Cu")
		(at 312.578242 -38.763448)
		(property "Reference" "R1499"
			(at 0 0 0)
			(layer "B.SilkS")
			(hide yes)
			(effects
				(font
					(size 1.27 1.27)
				)
				(justify mirror)
			)
		)
		(property "Value" ""
			(at 0 0 0)
			(layer "B.Fab")
			(effects
				(font
					(size 1.27 1.27)
				)
				(justify mirror)
			)
		)
		(duplicate_pad_numbers_are_jumpers no)
		(fp_line
			(start -0.7874 -0.4064)
			(end -0.7874 0.4064)
			(stroke
				(width 0.1524)
				(type default)
			)
			(layer "B.SilkS")
		)
		(fp_line
			(start -0.7874 0.4064)
			(end 0.7874 0.4064)
			(stroke
				(width 0.1524)
				(type default)
			)
			(layer "B.SilkS")
		)
		(fp_line
			(start 0.7874 -0.4064)
			(end -0.7874 -0.4064)
			(stroke
				(width 0.1524)
				(type default)
			)
			(layer "B.SilkS")
		)
		(fp_line
			(start 0.7874 0.4064)
			(end 0.7874 -0.4064)
			(stroke
				(width 0.1524)
				(type default)
			)
			(layer "B.SilkS")
		)
		(fp_line
			(start -0.67945 -0.3048)
			(end -0.67945 0.3048)
			(stroke
				(width 0.1)
				(type default)
			)
			(layer "B.Fab")
		)
		(fp_line
			(start -0.67945 0.3048)
			(end -0.120396 0.3048)
			(stroke
				(width 0.1)
				(type default)
			)
			(layer "B.Fab")
		)
		(fp_line
			(start -0.12065 -0.3048)
			(end -0.67945 -0.3048)
			(stroke
				(width 0.1)
				(type default)
			)
			(layer "B.Fab")
		)
		(fp_line
			(start -0.12065 -0.2794)
			(end -0.12065 -0.3048)
			(stroke
				(width 0.1)
				(type default)
			)
			(layer "B.Fab")
		)
		(fp_line
			(start -0.120396 0.2794)
			(end 0.12065 0.2794)
			(stroke
				(width 0.1)
				(type default)
			)
			(layer "B.Fab")
		)
		(fp_line
			(start -0.120396 0.3048)
			(end -0.120396 0.2794)
			(stroke
				(width 0.1)
				(type default)
			)
			(layer "B.Fab")
		)
		(fp_line
			(start 0.12065 -0.305054)
			(end 0.12065 -0.2794)
			(stroke
				(width 0.1)
				(type default)
			)
			(layer "B.Fab")
		)
		(fp_line
			(start 0.12065 -0.2794)
			(end -0.12065 -0.2794)
			(stroke
				(width 0.1)
				(type default)
			)
			(layer "B.Fab")
		)
		(fp_line
			(start 0.12065 0.2794)
			(end 0.12065 0.3048)
			(stroke
				(width 0.1)
				(type default)
			)
			(layer "B.Fab")
		)
		(fp_line
			(start 0.12065 0.3048)
			(end 0.67945 0.3048)
			(stroke
				(width 0.1)
				(type default)
			)
			(layer "B.Fab")
		)
		(fp_line
			(start 0.67945 -0.305054)
			(end 0.12065 -0.305054)
			(stroke
				(width 0.1)
				(type default)
			)
			(layer "B.Fab")
		)
		(fp_line
			(start 0.67945 0.3048)
			(end 0.67945 -0.305054)
			(stroke
				(width 0.1)
				(type default)
			)
			(layer "B.Fab")
		)
		(pad "1" smd circle
			(at 0.40005 0 180)
			(size 0 0)
			(layers "B.Cu" "B.Mask" "B.Paste")
			(net "FM_BIOS_ADV_FUNCTIONS")
		)
		(pad "2" smd circle
			(at -0.40005 0 180)
			(size 0 0)
			(layers "B.Cu" "B.Mask" "B.Paste")
			(net "GND")
		)
	)
)
